FILE_TYPE = MULTI_PHYS_TABLE;

PART 'Q_FUSE'

{========================================================================================}
:PACK_TYPE  | VALUE        | MATERIAL | PART_NUMBER              = STANDARD        | LIFECYCLE      | PART_NUMBER              | JEDEC_TYPE             | CLASS | DESCRIPTION                                     | COMPONENT_TYPE | LEAD_LENGTH | LPID | DAY        ;
{========================================================================================}
 'SMLF'     | '1.1A'       | 'IC'     | 'TMP_QDK110TPU110'(!)    = 'End of Design' | 'Comp-Approve' | 'DK110TPU110'            |'F1812'| 'IC'  | '1.1A'                                          | 'CHIP'         | ''          | ''   | ''        
 'SMLF'     | '1.1A'       | 'EMPTY'  | 'TMP_QDK110TPU110'(!)    = 'End of Design' | 'Comp-Approve' | 'DK110TPU110'            |'F1812'| 'IO'  | '1.1A'                                          | 'CHIP'         | ''          | ''   | ''        
 'SMLF'     | '4.5A'       | 'IC'     | 'TMP_QDK450WFU004'(!)    = ''              | ''             | 'DK450WFU004'            |'F1206'| 'IC'  | '4.5A'                                          | 'CHIP'         | ''          | ''   | ''        
 'SMLF'     | '4.5A'       | 'EMPTY'  | 'TMP_QDK450WFU004'(!)    = ''              | ''             | 'DK450WFU004'            |'F1206'| 'IO'  | '4.5A'                                          | 'CHIP'         | ''          | ''   | ''        
 'SMLF'     | '3A'         | 'IC'     | 'TMP_QDK300UFU000'(!)    = ''              | ''             | 'DK300UFU000'            |'F1206'| 'IC'  | '3A'                                            | 'CHIP'         | ''          | ''   | ''        
 'SMLF'     | '3A'         | 'EMPTY'  | 'TMP_QDK300UFU000'(!)    = ''              | ''             | 'DK300UFU000'            |'F1206'| 'IO'  | '3A'                                            | 'CHIP'         | ''          | ''   | ''        
 'SMLF'     | '5A/32V'     | 'IC'     | 'TMP_QDK500WFU011'(!)    = 'End of Design' | 'Comp-Approve' | 'DK500WFU011'            |'F1206'| 'IC'  | 'FUSE SMD 5A/ 32V/3216(FAST,UL/CSA)'            | 'CHIP'         | ''          | ''   | ''        
 'SMLF'     | '5A/32V'     | 'EMPTY'  | 'TMP_QDK500WFU011'(!)    = 'End of Design' | 'Comp-Approve' | 'DK500WFU011'            |'F1206'| 'IO'  | 'FUSE SMD 5A/ 32V/3216(FAST,UL/CSA)'            | 'CHIP'         | ''          | ''   | ''        
 'SMLF'     | '1.5A/63V'   | 'IC'     | 'TMP-C_S2I_0911_MASON_1'(!) = ''              | ''             | 'TMP-C_S2I_0911_MASON_1' |'F1206'| 'IC'  | 'FUSE SMD 1.5A 63V FAST(TR/3216FF1.5-R)'        | 'CHIP'         | ''          | ''   | ''        
 'SMLF'     | '1.5A/63V'   | 'EMPTY'  | 'TMP-C_S2I_0911_MASON_1'(!) = ''              | ''             | 'TMP-C_S2I_0911_MASON_1' |'F1206'| 'IO'  | 'FUSE SMD 1.5A 63V FAST(TR/3216FF1.5-R)'        | 'CHIP'         | ''          | ''   | ''        
 'SMLF'     | '1.6A/9V'    | 'IC'     | 'TMP_QDK160TPU113'(!)    = ''              | ''             | 'DK160TPU113'            |'F1812'| 'IC'  | 'FUSE SMD 1.6A 9V POLY(MINISMDC160F-2)'         | 'CHIP'         | ''          | ''   | ''        
 'SMLF'     | '1.6A/9V'    | 'EMPTY'  | 'TMP_QDK160TPU113'(!)    = ''              | ''             | 'DK160TPU113'            |'F1812'| 'IO'  | 'FUSE SMD 1.6A 9V POLY(MINISMDC160F-2)'         | 'CHIP'         | ''          | ''   | ''        
 'SMLF'     | '1.5A/6V'    | 'IC'     | 'QN-DK150TPU030'(!)      = 'End of Design' | 'Comp-Approve' | 'DK150TPU030'            |'F1206_H56'| 'IC'  | 'FUSE SMD 1.5A,6V(POLY,NANOSMDC150F-2)'         | 'CHIP'         | ''          | ''   | ''        
 'SMLF'     | '1.5A/6V'    | 'EMPTY'  | 'QN-DK150TPU030'(!)      = 'End of Design' | 'Comp-Approve' | 'DK150TPU030'            |'F1206_H56'| 'IO'  | 'FUSE SMD 1.5A,6V(POLY,NANOSMDC150F-2)'         | 'CHIP'         | ''          | ''   | ''        
 'SMLF'     | '3A/6V'      | 'IC'     | 'TMP-C_S2I_0421_MASON_1'(!) = ''              | ''             | 'TMP-C_S2I_0421_MASON_1' |'F2920_3'| 'IC'  | 'FUSE SMD 3A 6V POLY(SMD300F,UL/CSA)'           | 'CHIP'         | ''          | ''   | ''        
 'SMLF'     | '3A/6V'      | 'EMPTY'  | 'TMP-C_S2I_0421_MASON_1'(!) = ''              | ''             | 'TMP-C_S2I_0421_MASON_1' |'F2920_3'| 'IO'  | 'FUSE SMD 3A 6V POLY(SMD300F,UL/CSA)'           | 'CHIP'         | ''          | ''   | ''        
 'SMLF'     | '1.5A/6V'    | 'IC'     | 'TMP-C_S2I_0422_MASON_1'(!) = ''              | ''             | 'TMP-C_S2I_0422_MASON_1' |'F1206'| 'IC'  | 'FUSE SMD 1.5A 6V POLY(nanoSMDC150F,UL/CSA)'    | 'CHIP'         | ''          | ''   | ''        
 'SMLF'     | '1.5A/6V'    | 'EMPTY'  | 'TMP-C_S2I_0422_MASON_1'(!) = ''              | ''             | 'TMP-C_S2I_0422_MASON_1' |'F1206'| 'IO'  | 'FUSE SMD 1.5A 6V POLY(nanoSMDC150F,UL/CSA)'    | 'CHIP'         | ''          | ''   | ''        
 'SMLF'     | '0.5A/13.2V' | 'IC'     | 'TMP_QDK050SPU017'(!)    = 'End of Design' | 'Comp-Approve' | 'DK050SPU017'            |'F1206'| 'IC'  | 'FUSE SMD 0.5A,13.2V(POLY,NANOSMDC050F)'        | 'CHIP'         | ''          | ''   | ''        
 'SMLF'     | '0.5A/13.2V' | 'EMPTY'  | 'TMP_QDK050SPU017'(!)    = 'End of Design' | 'Comp-Approve' | 'DK050SPU017'            |'F1206'| 'IO'  | 'FUSE SMD 0.5A,13.2V(POLY,NANOSMDC050F)'        | 'CHIP'         | ''          | ''   | ''        
 'SMLF'     | '1.5A 32V'   | 'IC'     | 'TMP_QDK150WFU000'(!)    = 'End of Design' | 'Comp-Approve' | 'DK150WFU000'            |'F0603_H19'| 'IC'  | 'FUSE SMD 1.5A 32V(FAST,UL/CSA,0603)'           | 'CHIP'         | ''          | ''   | ''        
 'SMLF'     | '1.5A 32V'   | 'EMPTY'  | 'TMP_QDK150WFU000'(!)    = 'End of Design' | 'Comp-Approve' | 'DK150WFU000'            |'F0603_H19'| 'IO'  | 'FUSE SMD 1.5A 32V(FAST,UL/CSA,0603)'           | 'CHIP'         | ''          | ''   | ''        
 'SMLF'     | '6A,24V'     | 'IC'     | 'TMP_QDK600VPU004'(!)    = ''              | 'End of Life'  | 'DK600VPU004'            |'F1206_EOL'| 'IC'  | 'FUSE SMD 6A,24V POLY(1206SFS600F/24-2)'        | 'CHIP'         | ''          | ''   | ''        
 'SMLF'     | '6A,24V'     | 'EMPTY'  | 'TMP_QDK600VPU004'(!)    = ''              | 'End of Life'  | 'DK600VPU004'            |'F1206_EOL'| 'IO'  | 'FUSE SMD 6A,24V POLY(1206SFS600F/24-2)'        | 'CHIP'         | ''          | ''   | ''        
 'SMLF'     | '10A/125V'   | 'IC'     | 'TMP_QDKA00XFU409'(!)    = ''              | ''             | 'DKA00XFU409'            |'F2410'| 'IC'  | 'FUSE SMD 10A/125V(FAST,UL/CSA)'                | 'CHIP'         | ''          | ''   | ''        
 'SMLF'     | '10A/125V'   | 'EMPTY'  | 'TMP_QDKA00XFU409'(!)    = ''              | ''             | 'DKA00XFU409'            |'F2410'| 'IO'  | 'FUSE SMD 10A/125V(FAST,UL/CSA)'                | 'CHIP'         | ''          | ''   | ''        
 'SMLF'     | '.75A/13.2V' | 'IC'     | 'DK075SPU002'(!)         = ''              | ''             | 'DK075SPU002'            |'F1812'| 'IC'  | 'FUSE SMD .75A,13.2V(POLY,MINISMDC075F)LF'      | 'CHIP'         | ''          | ''   | ''        
 'SMLF'     | '.75A/13.2V' | 'EMPTY'  | 'DK075SPU002'(!)         = ''              | ''             | 'DK075SPU002'            |'F1812'| 'IO'  | 'FUSE SMD .75A,13.2V(POLY,MINISMDC075F)LF'      | 'CHIP'         | ''          | ''   | ''        
 'SMLF'     | '1.1A/16V'   | 'IC'     | 'DK110SPU001'(!)         = 'End of Design' | 'Comp-Approve' | 'DK110SPU001'            |'F1812'| 'IC'  | 'FUSE SMD 1.1A 16V POLY(MF-MSMF110/16)'         | 'CHIP'         | ''          | ''   | ''        
 'SMLF'     | '1.1A/16V'   | 'EMPTY'  | 'DK110SPU001'(!)         = 'End of Design' | 'Comp-Approve' | 'DK110SPU001'            |'F1812'| 'IO'  | 'FUSE SMD 1.1A 16V POLY(MF-MSMF110/16)'         | 'CHIP'         | ''          | ''   | ''        
 'SMLF'     | '3A/15V'     | 'IC'     | 'DK300SPU002'(!)         = ''              | ''             | 'DK300SPU002'            |'F2920_3'| 'IC'  | 'FUSE SMD 3A,15V,POLY(SMD300F/15)'              | 'CHIP'         | ''          | ''   | ''        
 'SMLF'     | '3A/15V'     | 'EMPTY'  | 'DK300SPU002'(!)         = ''              | ''             | 'DK300SPU002'            |'F2920_3'| 'IO'  | 'FUSE SMD 3A,15V,POLY(SMD300F/15)'              | 'CHIP'         | ''          | ''   | ''        
 'SMLF'     | '1.1A/8V'    | 'IC'     | 'DK110TPU012'(!)         = 'End of Design' | 'Comp-Approve' | 'DK110TPU012'            |'F1812'| 'IC'  | 'FUSE SMD 1.1A,8V(POLY,MINISMDC110F-2)'         | 'CHIP'         | ''          | ''   | '20101005'
 'SMLF'     | '1.1A/8V'    | 'EMPTY'  | 'DK110TPU012'(!)         = 'End of Design' | 'Comp-Approve' | 'DK110TPU012'            |'F1812'| 'IO'  | 'FUSE SMD 1.1A,8V(POLY,MINISMDC110F-2)'         | 'CHIP'         | ''          | ''   | '20101005'
 'SMLF'     | '1.5A/6V'    | 'IC'     | 'DK150TPU072'(!)         = ''              | 'End of Life'  | 'DK150TPU072'            |'F1206_EOL'| 'IC'  | 'FUSE SMD 1.5A,6V(POLY,1206L150PR)'             | 'CHIP'         | ''          | ''   | '20110207'
 'SMLF'     | '1.5A/6V'    | 'EMPTY'  | 'DK150TPU072'(!)         = ''              | 'End of Life'  | 'DK150TPU072'            |'F1206_EOL'| 'IO'  | 'FUSE SMD 1.5A,6V(POLY,1206L150PR)'             | 'CHIP'         | ''          | ''   | '20110207'
 'SMLF'     | '1.1A/6V'    | 'IC'     | 'DK110TPU501'(!)         = 'End of Design' | 'Comp-Approve' | 'DK110TPU501'            |'F1206'| 'IC'  | 'FUSE SMD 1.1A6V POLY(NANOSMDC110F-2)1206'      | 'CHIP'         | ''          | ''   | '20110217'
 'SMLF'     | '1.1A/6V'    | 'EMPTY'  | 'DK110TPU501'(!)         = 'End of Design' | 'Comp-Approve' | 'DK110TPU501'            |'F1206'| 'IO'  | 'FUSE SMD 1.1A6V POLY(NANOSMDC110F-2)1206'      | 'CHIP'         | ''          | ''   | '20110217'
 'SMLF'     | '5A/125V'    | 'IC'     | 'DK500XFU001'(!)         = ''              | ''             | 'DK500XFU001'            |'F2410'| 'IC'  | 'FUSE SMD 5A/125V(FAST,UL/CSA)0451005.MRL'      | 'CHIP'         | ''          | ''   | '20120224'
 'SMLF'     | '5A/125V'    | 'EMPTY'  | 'DK500XFU001'(!)         = ''              | ''             | 'DK500XFU001'            |'F2410'| 'IO'  | 'FUSE SMD 5A/125V(FAST,UL/CSA)0451005.MRL'      | 'CHIP'         | ''          | ''   | '20120224'
 'SMLF'     | '3A/15V'     | 'IC'     | 'DK300SPU000'(!)         = ''              | ''             | 'DK300SPU000'            |'F2920_1-25'| 'IC'  | 'FUSE SMD 3A 15V POLY(2920L300/15DR)'           | 'CHIP'         | ''          | ''   | '20120306'
 'SMLF'     | '3A/15V'     | 'EMPTY'  | 'DK300SPU000'(!)         = ''              | ''             | 'DK300SPU000'            |'F2920_1-25'| 'IO'  | 'FUSE SMD 3A 15V POLY(2920L300/15DR)'           | 'CHIP'         | ''          | ''   | '20120306'
 'SMLF'     | '2A/6V'      | 'IC'     | 'DK200TPU004'(!)         = 'End of Design' | 'Comp-Approve' | 'DK200TPU004'            |'F1206'| 'IC'  | 'FUSE SMD 2A 6V(POLY,UL/CSA,1206)'              | 'CHIP'         | ''          | ''   | '20120421'
 'SMLF'     | '2A/6V'      | 'EMPTY'  | 'DK200TPU004'(!)         = 'End of Design' | 'Comp-Approve' | 'DK200TPU004'            |'F1206'| 'IO'  | 'FUSE SMD 2A 6V(POLY,UL/CSA,1206)'              | 'CHIP'         | ''          | ''   | '20120421'
 'THLF'     | '9A/16V'     | 'IC'     | 'DK900SPU001'(!)         = ''              | ''             | 'DK900SPU001'            |'F1255_16R900GMR'| 'IC'  | 'FUSE DIP 9A/16V (POLY,UL/TUV)16R900GMR'        | 'CHIP'         | ''          | ''   | '20120314'
 'THLF'     | '9A/16V'     | 'EMPTY'  | 'DK900SPU001'(!)         = ''              | ''             | 'DK900SPU001'            |'F1255_16R900GMR'| 'IO'  | 'FUSE DIP 9A/16V (POLY,UL/TUV)16R900GMR'        | 'CHIP'         | ''          | ''   | '20120314'
 'THLF'     | '14A/16V'    | 'IC'     | 'DKE00SPU000'(!)         = ''              | ''             | 'DKE00SPU000'            |'F9314_16R1400GH'| 'IC'  | 'FUSE DIP 14A/16V(POLY,UL/TUV)16R1400GH'        | 'CHIP'         | ''          | ''   | '20120314'
 'THLF'     | '14A/16V'    | 'EMPTY'  | 'DKE00SPU000'(!)         = ''              | ''             | 'DKE00SPU000'            |'F9314_16R1400GH'| 'IO'  | 'FUSE DIP 14A/16V(POLY,UL/TUV)16R1400GH'        | 'CHIP'         | ''          | ''   | '20120314'
 'THLF_SEL' | '9A/16V'     | 'IC'     | 'SP_DK900SPU001'(!)      = ''              | ''             | 'DK900SPU001'            |'G_F1255_16R900GMR'| 'IC'  | 'FUSE DIP 9A/16V (POLY,UL/TUV)16R900GMR'        | 'CHIP'         | ''          | ''   | '20120314'
 'THLF_SEL' | '9A/16V'     | 'EMPTY'  | 'SP_DK900SPU001'(!)      = ''              | ''             | 'DK900SPU001'            |'G_F1255_16R900GMR'| 'IO'  | 'FUSE DIP 9A/16V (POLY,UL/TUV)16R900GMR'        | 'CHIP'         | ''          | ''   | '20120314'
 'THLF_SEL' | '14A/16V'    | 'IC'     | 'SP_DKE00SPU000'(!)      = ''              | ''             | 'DKE00SPU000'            |'G_F9314_16R1400GH'| 'IC'  | 'FUSE DIP 14A/16V(POLY,UL/TUV)16R1400GH'        | 'CHIP'         | ''          | ''   | '20120314'
 'THLF_SEL' | '14A/16V'    | 'EMPTY'  | 'SP_DKE00SPU000'(!)      = ''              | ''             | 'DKE00SPU000'            |'G_F9314_16R1400GH'| 'IO'  | 'FUSE DIP 14A/16V(POLY,UL/TUV)16R1400GH'        | 'CHIP'         | ''          | ''   | '20120314'
 'SMLF'     | '0.5A'       | 'IC'     | 'DK050SPU033'(!)         = ''              | ''             | 'DK050SPU033'            |'F1812'| 'IC'  | 'FUSE SMD 0.5A 15V POLY(SMD1812P050TF)'         | 'CHIP'         | ''          | ''   | '20120525'
 'SMLF'     | '0.5A'       | 'EMPTY'  | 'DK050SPU033'(!)         = ''              | ''             | 'DK050SPU033'            |'F1812'| 'IO'  | 'FUSE SMD 0.5A 15V POLY(SMD1812P050TF)'         | 'CHIP'         | ''          | ''   | '20120525'
 'SMLF'     | '2.6A'       | 'IC'     | 'DK260TPU001'(!)         = 'End of Design' | 'Comp-Approve' | 'DK260TPU001'            |'F1812'| 'IC'  | 'FUSE SMD 2.6A,6V(POLY,MINISMDC260F)'           | 'CHIP'         | ''          | ''   | '20120627'
 'SMLF'     | '2.6A'       | 'EMPTY'  | 'DK260TPU001'(!)         = 'End of Design' | 'Comp-Approve' | 'DK260TPU001'            |'F1812'| 'IO'  | 'FUSE SMD 2.6A,6V(POLY,MINISMDC260F)'           | 'CHIP'         | ''          | ''   | '20120627'
 'SMLF'     | '8A/32V'     | 'IC'     | 'DK800WFU000'(!)         = ''              | ''             | 'DK800WFU000'            |'F1206'| 'IC'  | 'FUSE SMD 8A 32V(FAST,0437008.WR,1206)'         | 'CHIP'         | ''          | ''   | '20120628'
 'SMLF'     | '8A/32V'     | 'EMPTY'  | 'DK800WFU000'(!)         = ''              | ''             | 'DK800WFU000'            |'F1206'| 'IO'  | 'FUSE SMD 8A 32V(FAST,0437008.WR,1206)'         | 'CHIP'         | ''          | ''   | '20120628'
 'SMLF'     | '3A/24V'     | 'IC'     | 'DK300VPU000'(!)         = 'End of Design' | 'Comp-Approve' | 'DK300VPU000'            |'F2920_1-6'| 'IC'  | 'FUSE SMD 3A 24V POLY(MF-LSMF300/24X-2)'        | 'CHIP'         | ''          | ''   | '20120706'
 'SMLF'     | '3A/24V'     | 'EMPTY'  | 'DK300VPU000'(!)         = 'End of Design' | 'Comp-Approve' | 'DK300VPU000'            |'F2920_1-6'| 'IO'  | 'FUSE SMD 3A 24V POLY(MF-LSMF300/24X-2)'        | 'CHIP'         | ''          | ''   | '20120706'
 'SMLF'     | '0.35A/6V'   | 'IC'     | 'DK035TPU000'(!)         = ''              | ''             | 'DK035TPU000'            |'F0603_H62'| 'IC'  | 'FUSE SMD 0.35A.6V(POLY.SMD0603P035TF)'         | 'CHIP'         | ''          | ''   | '20120914'
 'SMLF'     | '0.35A/6V'   | 'EMPTY'  | 'DK035TPU000'(!)         = ''              | ''             | 'DK035TPU000'            |'F0603_H62'| 'IO'  | 'FUSE SMD 0.35A.6V(POLY.SMD0603P035TF)'         | 'CHIP'         | ''          | ''   | '20120914'
 'SMLF'     | '1.1A/8V'    | 'IC'     | 'DK110TPU003'(!)         = ''              | ''             | 'DK110TPU003'            |'F1206'| 'IC'  | 'FUSE SMD 1.1A 8V POLY(SMD1206P110TFT)'         | 'CHIP'         | ''          | ''   | '20120915'
 'SMLF'     | '1.1A/8V'    | 'EMPTY'  | 'DK110TPU003'(!)         = ''              | ''             | 'DK110TPU003'            |'F1206'| 'IO'  | 'FUSE SMD 1.1A 8V POLY(SMD1206P110TFT)'         | 'CHIP'         | ''          | ''   | '20120915'
 'SMLF'     | '100ohm/4A'  | 'IC'     | 'CX12S101001'(!)         = 'End of Design' | 'End of Life'  | 'CX12S101001'            |'L0805_EOL'| 'IC'  | 'EMI FIL CHIP MPZ2012S101AT(100.4A)L-F'         | 'CHIP'         | ''          | ''   | '20121106'
 'SMLF'     | '100ohm/4A'  | 'EMPTY'  | 'CX12S101001'(!)         = 'End of Design' | 'End of Life'  | 'CX12S101001'            |'L0805_EOL'| 'IO'  | 'EMI FIL CHIP MPZ2012S101AT(100.4A)L-F'         | 'CHIP'         | ''          | ''   | '20121106'
 'SMLF'     | '6A/24V'     | 'IC'     | 'DK600VSU006'(!)         = 'End of Design' | 'End of Life'  | 'DK600VSU006'            |'F1206_EOL'| 'IC'  | 'FUSE SMD 6A 24V SLOW(1206SFS600F/24-2)'        | 'CHIP'         | ''          | ''   | '20130415'
 'SMLF'     | '6A/24V'     | 'EMPTY'  | 'DK600VSU006'(!)         = 'End of Design' | 'End of Life'  | 'DK600VSU006'            |'F1206_EOL'| 'IO'  | 'FUSE SMD 6A 24V SLOW(1206SFS600F/24-2)'        | 'CHIP'         | ''          | ''   | '20130415'
 'SMLF'     | '40A/60V'    | 'IC'     | 'DKZ00ZFU000'(!)         = ''              | ''             | 'DKZ00ZFU000'            |'F5018'| 'IC'  | 'FUSE SMD 40A/60V(FAST,UL/CSA)'                 | 'CHIP'         | ''          | ''   | '20130503'
 'SMLF'     | '40A/60V'    | 'EMPTY'  | 'DKZ00ZFU000'(!)         = ''              | ''             | 'DKZ00ZFU000'            |'F5018'| 'IO'  | 'FUSE SMD 40A/60V(FAST,UL/CSA)'                 | 'CHIP'         | ''          | ''   | '20130503'
 'SMLF'     | '25A/24V'    | 'IC'     | 'DKQ00VFU000'(!)         = ''              | ''             | 'DKQ00VFU000'            |'F1206XA'| 'IC'  | 'FUSE SMD 25A 24V(FAST.UL/CSA.1206)'            | 'CHIP'         | ''          | ''   | '20130509'
 'SMLF'     | '25A/24V'    | 'EMPTY'  | 'DKQ00VFU000'(!)         = ''              | ''             | 'DKQ00VFU000'            |'F1206XA'| 'IO'  | 'FUSE SMD 25A 24V(FAST.UL/CSA.1206)'            | 'CHIP'         | ''          | ''   | '20130509'
 'SMLF'     | '2.0A/8V'    | 'IC'     | 'DK200TPU001'(!)         = 'End of Design' | 'Comp-Approve' | 'DK200TPU001'            |'F1812XC'| 'IC'  | 'FUSE SMD 2.0A 8V POLY(MINISMDC200F-2)'         | 'CHIP'         | ''          | ''   | '20130527'
 'SMLF'     | '2.0A/8V'    | 'EMPTY'  | 'DK200TPU001'(!)         = 'End of Design' | 'Comp-Approve' | 'DK200TPU001'            |'F1812XC'| 'IO'  | 'FUSE SMD 2.0A 8V POLY(MINISMDC200F-2)'         | 'CHIP'         | ''          | ''   | '20130527'
 'SMLF'     | '15A/24V'    | 'IC'     | 'DKF00VFU003'(!)         = ''              | ''             | 'DKF00VFU003'            |'F1206XC'| 'IC'  | 'FUSE SMD 15A 24V(FAST,UL/CSA,1206)'            | 'CHIP'         | ''          | ''   | '20130605'
 'SMLF'     | '15A/24V'    | 'EMPTY'  | 'DKF00VFU003'(!)         = ''              | ''             | 'DKF00VFU003'            |'F1206XC'| 'IO'  | 'FUSE SMD 15A 24V(FAST,UL/CSA,1206)'            | 'CHIP'         | ''          | ''   | '20130605'
 'SMLF'     | '5A/24V'     | 'IC'     | 'DK500VFU113'(!)         = ''              | ''             | 'DK500VFU113'            |'F1206XB'| 'IC'  | 'FUSE SMD 5A/ 24V(FAST,UL/CSA)'                 | 'CHIP'         | ''          | ''   | '20130815'
 'SMLF'     | '5A/24V'     | 'EMPTY'  | 'DK500VFU113'(!)         = ''              | ''             | 'DK500VFU113'            |'F1206XB'| 'IO'  | 'FUSE SMD 5A/ 24V(FAST,UL/CSA)'                 | 'CHIP'         | ''          | ''   | '20130815'
 'SMLF'     | '0.55A/60V'  | 'IC'     | 'DK055ZPU000'(!)         = ''              | ''             | 'DK055ZPU000'            |'F2016'| 'IC'  | 'FUSE SMD 0.55A60V(POLY,UL/TUV)2016L050MR'      | 'CHIP'         | ''          | ''   | '20140212'
 'SMLF'     | '0.55A/60V'  | 'EMPTY'  | 'DK055ZPU000'(!)         = ''              | ''             | 'DK055ZPU000'            |'F2016'| 'IO'  | 'FUSE SMD 0.55A60V(POLY,UL/TUV)2016L050MR'      | 'CHIP'         | ''          | ''   | '20140212'
 'SMLF'     | '1.5A/24V'   | 'IC'     | 'DK150VPU027'(!)         = ''              | ''             | 'DK150VPU027'            |'F1812XA'| 'IC'  | 'FUSE SMD 1.5A 24V(POLY,UL/CSA/TUV)'            | 'CHIP'         | ''          | ''   | '20140227'
 'SMLF'     | '1.5A/24V'   | 'EMPTY'  | 'DK150VPU027'(!)         = ''              | ''             | 'DK150VPU027'            |'F1812XA'| 'IO'  | 'FUSE SMD 1.5A 24V(POLY,UL/CSA/TUV)'            | 'CHIP'         | ''          | ''   | '20140227'
 'SMLF'     | '45A/24V'    | 'IC'     | 'DKZ00VFU105'(!)         = ''              | 'End of Life'  | 'DKZ00VFU105'            |'F0603_H19_EOL'| 'IC'  | 'FUSE 45A 24V PGB1010603NR(0603)'               | 'CHIP'         | ''          | ''   | '20140227'
 'SMLF'     | '45A/24V'    | 'EMPTY'  | 'DKZ00VFU105'(!)         = ''              | 'End of Life'  | 'DKZ00VFU105'            |'F0603_H19_EOL'| 'IO'  | 'FUSE 45A 24V PGB1010603NR(0603)'               | 'CHIP'         | ''          | ''   | '20140227'
 'SMLF'     | '0.75A/6V'   | 'IC'     | 'DK075TPU031'(!)         = 'End of Design' | 'Comp-Approve' | 'DK075TPU031'            |'F1206XF'| 'IC'  | 'FUSE SMD 0.75A,6V(POLY,NANOSMDC075F-2)'        | 'CHIP'         | ''          | ''   | '20140227'
 'SMLF'     | '0.75A/6V'   | 'EMPTY'  | 'DK075TPU031'(!)         = 'End of Design' | 'Comp-Approve' | 'DK075TPU031'            |'F1206XF'| 'IO'  | 'FUSE SMD 0.75A,6V(POLY,NANOSMDC075F-2)'        | 'CHIP'         | ''          | ''   | '20140227'
 'SMLF'     | '3A/6V'      | 'IC'     | 'DK300TPU001'(!)         = ''              | ''             | 'DK300TPU001'            |'F1812XD'| 'IC'  | 'FUSE SMD 3A 6V POLY(MINISMDC300F)'             | 'CHIP'         | ''          | ''   | '20140227'
 'SMLF'     | '3A/6V'      | 'EMPTY'  | 'DK300TPU001'(!)         = ''              | ''             | 'DK300TPU001'            |'F1812XD'| 'IO'  | 'FUSE SMD 3A 6V POLY(MINISMDC300F)'             | 'CHIP'         | ''          | ''   | '20140227'
 'SMLF'     | '2A/15V'     | 'IC'     | 'DK200SPU000'(!)         = ''              | ''             | 'DK200SPU000'            |'F2920_1-25XA'| 'IC'  | 'FUSE SMD 2A,15V(POLY,2920L200PR)'              | 'CHIP'         | ''          | ''   | '20140331'
 'SMLF'     | '2A/15V'     | 'EMPTY'  | 'DK200SPU000'(!)         = ''              | ''             | 'DK200SPU000'            |'F2920_1-25XA'| 'IO'  | 'FUSE SMD 2A,15V(POLY,2920L200PR)'              | 'CHIP'         | ''          | ''   | '20140331'
 'SMLF'     | '8A/24V'     | 'IC'     | 'DK800VFU001'(!)         = 'End of Design' | 'Comp-Approve' | 'DK800VFU001'            |'F1206XG'| 'IC'  | 'FUSE SMD 8A/24V/F1206FA8000(FAST,UL/CSA)'      | 'CHIP'         | ''          | ''   | '20140403'
 'SMLF'     | '8A/24V'     | 'EMPTY'  | 'DK800VFU001'(!)         = 'End of Design' | 'Comp-Approve' | 'DK800VFU001'            |'F1206XG'| 'IO'  | 'FUSE SMD 8A/24V/F1206FA8000(FAST,UL/CSA)'      | 'CHIP'         | ''          | ''   | '20140403'
 'SMLF'     | '3A/24V'     | 'IC'     | 'DK300VPU001'(!)         = 'End of Design' | 'Comp-Approve' | 'DK300VPU001'            |'F2920_0-95'| 'IC'  | 'FUSE SMD 3A/24V(POLY,UL/CSA/TUV)'              | 'CHIP'         | ''          | ''   | '20140409'
 'SMLF'     | '3A/24V'     | 'EMPTY'  | 'DK300VPU001'(!)         = 'End of Design' | 'Comp-Approve' | 'DK300VPU001'            |'F2920_0-95'| 'IO'  | 'FUSE SMD 3A/24V(POLY,UL/CSA/TUV)'              | 'CHIP'         | ''          | ''   | '20140409'
 'SMLF'     | '0.75A/6V'   | 'IC'     | 'DK075TPU009'(!)         = ''              | ''             | 'DK075TPU009'            |'F0603_H30'| 'IC'  | 'FUSE SMD 0.75A 6V POLY(0603L075SLYR)'          | 'CHIP'         | ''          | ''   | '20140708'
 'SMLF'     | '0.75A/6V'   | 'EMPTY'  | 'DK075TPU009'(!)         = ''              | ''             | 'DK075TPU009'            |'F0603_H30'| 'IO'  | 'FUSE SMD 0.75A 6V POLY(0603L075SLYR)'          | 'CHIP'         | ''          | ''   | '20140708'
 'SMLF'     | '4.5A/6V'    | 'IC'     | 'DK450TPU000'(!)         = ''              | ''             | 'DK450TPU000'            |'F1210XA'| 'IC'  | 'FUSE SMD 4.5A 6V POLY(1210L450SLWR)'           | 'CHIP'         | ''          | ''   | '20140708'
 'SMLF'     | '4.5A/6V'    | 'EMPTY'  | 'DK450TPU000'(!)         = ''              | ''             | 'DK450TPU000'            |'F1210XA'| 'IO'  | 'FUSE SMD 4.5A 6V POLY(1210L450SLWR)'           | 'CHIP'         | ''          | ''   | '20140708'
 'SMLF'     | '2.82A/6V'   | 'IC'     | 'DK282TPU000'(!)         = ''              | ''             | 'DK282TPU000'            |'F1206XH'| 'IC'  | 'FUSE 2.82A 6V POLY UL/TUV(1206L380SLTH)'       | 'CHIP'         | ''          | ''   | '20141031'
 'SMLF'     | '2.82A/6V'   | 'EMPTY'  | 'DK282TPU000'(!)         = ''              | ''             | 'DK282TPU000'            |'F1206XH'| 'IO'  | 'FUSE 2.82A 6V POLY UL/TUV(1206L380SLTH)'       | 'CHIP'         | ''          | ''   | '20141031'
 'SMLF'     | '1A/6V'      | 'IC'     | 'DK100TPU004'(!)         = ''              | ''             | 'DK100TPU004'            |'F0603_H30'| 'IC'  | 'FUSE SMD 1A 6V POLY(SMD0603P100SLR)'           | 'CHIP'         | ''          | ''   | '20141218'
 'SMLF'     | '1A/6V'      | 'EMPTY'  | 'DK100TPU004'(!)         = ''              | ''             | 'DK100TPU004'            |'F0603_H30'| 'IO'  | 'FUSE SMD 1A 6V POLY(SMD0603P100SLR)'           | 'CHIP'         | ''          | ''   | '20141218'
 'THLF'     | '9.0A/16V'   | 'IC'     | 'DK900SPU000'(!)         = ''              | ''             | 'DK900SPU000'            |'F5512_RLD16P900GF'| 'IC'  | 'FUSE DIP 9.0A 16V POLY(RLD16P900GF)'           | 'CHIP'         | ''          | ''   | '20141218'
 'THLF'     | '9.0A/16V'   | 'EMPTY'  | 'DK900SPU000'(!)         = ''              | ''             | 'DK900SPU000'            |'F5512_RLD16P900GF'| 'IO'  | 'FUSE DIP 9.0A 16V POLY(RLD16P900GF)'           | 'CHIP'         | ''          | ''   | '20141218'
 'THLF'     | '9.0A/16V'   | 'IC'     | 'SP_DK900SPU000'(!)      = ''              | ''             | 'DK900SPU000'            |'G_F5512_RLD16P900GF'| 'IC'  | 'FUSE DIP 9.0A 16V POLY(RLD16P900GF)'           | 'CHIP'         | ''          | ''   | '20141218'
 'THLF'     | '9.0A/16V'   | 'EMPTY'  | 'SP_DK900SPU000'(!)      = ''              | ''             | 'DK900SPU000'            |'G_F5512_RLD16P900GF'| 'IO'  | 'FUSE DIP 9.0A 16V POLY(RLD16P900GF)'           | 'CHIP'         | ''          | ''   | '20141218'
 'SMLF'     | '5A/16V'     | 'IC'     | 'DK500SPU001'(!)         = ''              | ''             | 'DK500SPU001'            |'F2920_1-6'| 'IC'  | 'FUSE SMD 5A 16V POLY(2920L500/16MR)'           | 'CHIP'         | ''          | ''   | '20141223'
 'SMLF'     | '5A/16V'     | 'EMPTY'  | 'DK500SPU001'(!)         = ''              | ''             | 'DK500SPU001'            |'F2920_1-6'| 'IO'  | 'FUSE SMD 5A 16V POLY(2920L500/16MR)'           | 'CHIP'         | ''          | ''   | '20141223'
 'SMLF'     | '5A/16V'     | 'IC'     | 'DK500SPU002'(!)         = ''              | ''             | 'DK500SPU002'            |'F2920_1-6'| 'IC'  | 'FUSE SMD 5A 16V POLY(SMD2920P500TF/16)'        | 'CHIP'         | ''          | ''   | '20141223'
 'SMLF'     | '5A/16V'     | 'EMPTY'  | 'DK500SPU002'(!)         = ''              | ''             | 'DK500SPU002'            |'F2920_1-6'| 'IO'  | 'FUSE SMD 5A 16V POLY(SMD2920P500TF/16)'        | 'CHIP'         | ''          | ''   | '20141223'
 'SMLF'     | '4A/15V'     | 'IC'     | 'DK400SPU000'(!)         = ''              | ''             | 'DK400SPU000'            |'F2920_1-6'| 'IC'  | 'FUSE SMD 4A 15V POLY(SMD2920P400TF)'           | 'CHIP'         | ''          | ''   | '20141223'
 'SMLF'     | '4A/15V'     | 'EMPTY'  | 'DK400SPU000'(!)         = ''              | ''             | 'DK400SPU000'            |'F2920_1-6'| 'IO'  | 'FUSE SMD 4A 15V POLY(SMD2920P400TF)'           | 'CHIP'         | ''          | ''   | '20141223'
 'SMLF'     | '3.0A/15V'   | 'IC'     | 'DK300SPU001'(!)         = ''              | ''             | 'DK300SPU001'            |'F2920_1-25'| 'IC'  | 'FUSE 3.0A 15V POLY(SMD2920P300TF/15)'          | 'CHIP'         | ''          | ''   | '20141223'
 'SMLF'     | '3.0A/15V'   | 'EMPTY'  | 'DK300SPU001'(!)         = ''              | ''             | 'DK300SPU001'            |'F2920_1-25'| 'IO'  | 'FUSE 3.0A 15V POLY(SMD2920P300TF/15)'          | 'CHIP'         | ''          | ''   | '20141223'
 'SMLF'     | '1.5A/6V'    | 'IC'     | 'DK150TPU023'(!)         = ''              | ''             | 'DK150TPU023'            |'F0603_H40'| 'IC'  | 'FUSE SMD 1.5A 6V POLY(0603L150SLYR)'           | 'CHIP'         | ''          | ''   | '20141225'
 'SMLF'     | '1.5A/6V'    | 'EMPTY'  | 'DK150TPU023'(!)         = ''              | ''             | 'DK150TPU023'            |'F0603_H40'| 'IO'  | 'FUSE SMD 1.5A 6V POLY(0603L150SLYR)'           | 'CHIP'         | ''          | ''   | '20141225'
 'THLF'     | '11A/16V'    | 'IC'     | 'DKB00SPU000'(!)         = ''              | ''             | 'DKB00SPU000'            |'F6912_16R1100GMR'| 'IC'  | 'FUSE DIP 11A 16V POLY(16R1100GMR)'             | 'CHIP'         | ''          | ''   | '20141230'
 'THLF'     | '11A/16V'    | 'EMPTY'  | 'DKB00SPU000'(!)         = ''              | ''             | 'DKB00SPU000'            |'F6912_16R1100GMR'| 'IO'  | 'FUSE DIP 11A 16V POLY(16R1100GMR)'             | 'CHIP'         | ''          | ''   | '20141230'
 'SMLF'     | '1A/6V'      | 'IC'     | 'DK100TPU006'(!)         = ''              | ''             | 'DK100TPU006'            |'F0603_H30'| 'IC'  | 'FUSE SMD 1A 6V POLY(0603L100SLYR)'             | 'CHIP'         | ''          | ''   | '20150113'
 'SMLF'     | '1A/6V'      | 'EMPTY'  | 'DK100TPU006'(!)         = ''              | ''             | 'DK100TPU006'            |'F0603_H30'| 'IO'  | 'FUSE SMD 1A 6V POLY(0603L100SLYR)'             | 'CHIP'         | ''          | ''   | '20150113'
 'THLF'     | '8A/16V'     | 'IC'     | 'DK800SPU000'(!)         = ''              | ''             | 'DK800SPU000'            |'F5012_16R800G'| 'IC'  | 'FUSE DIP 8A/16V(POLY,UL/TUV)16R800GMR'         | 'CHIP'         | ''          | ''   | '20150202'
 'THLF'     | '8A/16V'     | 'EMPTY'  | 'DK800SPU000'(!)         = ''              | ''             | 'DK800SPU000'            |'F5012_16R800G'| 'IO'  | 'FUSE DIP 8A/16V(POLY,UL/TUV)16R800GMR'         | 'CHIP'         | ''          | ''   | '20150202'
 'THLF'     | '8A/16V'     | 'IC'     | 'SP_DK800SPU000'(!)      = ''              | ''             | 'DK800SPU000'            |'G_F5012_16R800G'| 'IC'  | 'FUSE DIP 8A/16V(POLY,UL/TUV)16R800GMR_FOR SEL' | 'CHIP'         | ''          | ''   | '20150202'
 'THLF'     | '8A/16V'     | 'EMPTY'  | 'SP_DK800SPU000'(!)      = ''              | ''             | 'DK800SPU000'            |'G_F5012_16R800G'| 'IO'  | 'FUSE DIP 8A/16V(POLY,UL/TUV)16R800GMR_FOR SEL' | 'CHIP'         | ''          | ''   | '20150202'
 'SMLF'     | '2.5A/16V'   | 'IC'     | 'DK250SPU000'(!)         = ''              | ''             | 'DK250SPU000'            |'F1812_2-25'| 'IC'  | 'FUSE SMD 2.5A 16V POLY(MF-MSMF250/16)'         | 'CHIP'         | ''          | ''   | '20150216'
 'SMLF'     | '2.5A/16V'   | 'EMPTY'  | 'DK250SPU000'(!)         = ''              | ''             | 'DK250SPU000'            |'F1812_2-25'| 'IO'  | 'FUSE SMD 2.5A 16V POLY(MF-MSMF250/16)'         | 'CHIP'         | ''          | ''   | '20150216'
 'SMLF'     | '5A/32V'     | 'IC'     | 'DK500WFU006'(!)         = ''              | ''             | 'DK500WFU006'            |'F0603_H19'| 'IC'  | 'FUSE SMD 5A 32V(FAST,0467005.NRHF,0603)'       | 'CHIP'         | ''          | ''   | '20150305'
 'SMLF'     | '5A/32V'     | 'EMPTY'  | 'DK500WFU006'(!)         = ''              | ''             | 'DK500WFU006'            |'F0603_H19'| 'IO'  | 'FUSE SMD 5A 32V(FAST,0467005.NRHF,0603)'       | 'CHIP'         | ''          | ''   | '20150305'
 'SMLF'     | '30A/250V'   | 'IC'     | 'DKV00YFU000'(!)         = ''              | ''             | 'DKV00YFU000'            |'F4012'| 'IC'  | 'FUSE SMD 30A 250V(FAST,UL)0463030.ER'          | 'CHIP'         | ''          | ''   | '20150331'
 'SMLF'     | '30A/250V'   | 'EMPTY'  | 'DKV00YFU000'(!)         = ''              | ''             | 'DKV00YFU000'            |'F4012'| 'IO'  | 'FUSE SMD 30A 250V(FAST,UL)0463030.ER'          | 'CHIP'         | ''          | ''   | '20150331'
 'SMLF'     | '0.05A/30V'  | 'IC'     | 'DK005WPU000'(!)         = 'End of Design' | 'Comp-Approve' | 'DK005WPU000'            |'F1210XA'| 'IC'  | 'FUSE SMD 0.05A 30V POLY(1210L005WR)'           | 'CHIP'         | ''          | ''   | '20150520'
 'SMLF'     | '0.05A/30V'  | 'EMPTY'  | 'DK005WPU000'(!)         = 'End of Design' | 'Comp-Approve' | 'DK005WPU000'            |'F1210XA'| 'IO'  | 'FUSE SMD 0.05A 30V POLY(1210L005WR)'           | 'CHIP'         | ''          | ''   | '20150520'
 'SMLF'     | '10A/63V'    | 'IC'     | 'DKA00UFU001'(!)         = ''              | ''             | 'DKA00UFU001'            |'F1206XE'| 'IC'  | 'FUSE SMD 10A 63V(FAST,UL,0458010.DR)'          | 'CHIP'         | ''          | ''   | '20150703'
 'SMLF'     | '10A/63V'    | 'EMPTY'  | 'DKA00UFU001'(!)         = ''              | ''             | 'DKA00UFU001'            |'F1206XE'| 'IO'  | 'FUSE SMD 10A 63V(FAST,UL,0458010.DR)'          | 'CHIP'         | ''          | ''   | '20150703'
 'SMLF'     | '2A/6V'      | 'IC'     | 'DK200TPU007'(!)         = ''              | ''             | 'DK200TPU007'            |'F1206XF_H44'| 'IC'  | 'FUSE SMD 2A 6V POLY (NANOSMDC200F)'            | 'CHIP'         | ''          | ''   | '20150811'
 'SMLF'     | '2A/6V'      | 'EMPTY'  | 'DK200TPU007'(!)         = ''              | ''             | 'DK200TPU007'            |'F1206XF_H44'| 'IO'  | 'FUSE SMD 2A 6V POLY (NANOSMDC200F)'            | 'CHIP'         | ''          | ''   | '20150811'
 'SMLF'     | '6.3A/75V'   | 'IC'     | 'DK630UFU000'(!)         = ''              | ''             | 'DK630UFU000'            |'F1206XE'| 'IC'  | 'FUSE SMD 6.3A 75V (FAST,UL)045806.3DR'         | 'CHIP'         | ''          | ''   | '20150922'
 'SMLF'     | '6.3A/75V'   | 'EMPTY'  | 'DK630UFU000'(!)         = ''              | ''             | 'DK630UFU000'            |'F1206XE'| 'IO'  | 'FUSE SMD 6.3A 75V (FAST,UL)045806.3DR'         | 'CHIP'         | ''          | ''   | '20150922'
 'SMLF'     | '3A/75V'     | 'IC'     | 'DK300UFU003'(!)         = ''              | ''             | 'DK300UFU003'            |'F1206XE'| 'IC'  | 'FUSE SMD 3A 75V (FAST,UL)0458003.DR'           | 'CHIP'         | ''          | ''   | '20150922'
 'SMLF'     | '3A/75V'     | 'EMPTY'  | 'DK300UFU003'(!)         = ''              | ''             | 'DK300UFU003'            |'F1206XE'| 'IO'  | 'FUSE SMD 3A 75V (FAST,UL)0458003.DR'           | 'CHIP'         | ''          | ''   | '20150922'
 'THLF'     | '8A/16V'     | 'IC'     | 'DK800SPU001'(!)         = ''              | ''             | 'DK800SPU001'            |'F5012_16R800G_H989'| 'IC'  | 'FUSE DIP 8A 16V POLY(16R800GKLMR)'             | 'CHIP'         | ''          | ''   | '20151117'
 'THLF'     | '8A/16V'     | 'EMPTY'  | 'DK800SPU001'(!)         = ''              | ''             | 'DK800SPU001'            |'F5012_16R800G_H989'| 'IO'  | 'FUSE DIP 8A 16V POLY(16R800GKLMR)'             | 'CHIP'         | ''          | ''   | '20151117'
 'THLF'     | '8A/16V'     | 'IC'     | 'SP_DK800SPU001'(!)      = ''              | ''             | 'SP_DK800SPU001'         |'G_F5012_16R800G_H989'| 'IC'  | 'FUSE DIP 8A 16V POLY(16R800GKLMR)_FOR SEL'     | 'CHIP'         | ''          | ''   | '20151117'
 'THLF'     | '8A/16V'     | 'EMPTY'  | 'SP_DK800SPU001'(!)      = ''              | ''             | 'SP_DK800SPU001'         |'G_F5012_16R800G_H989'| 'IO'  | 'FUSE DIP 8A 16V POLY(16R800GKLMR)_FOR SEL'     | 'CHIP'         | ''          | ''   | '20151117'
 'SMLF'     | '1A/32V'     | 'IC'     | 'DK100WFU009'(!)         = ''              | ''             | 'DK100WFU009'            |'F0603XA'| 'IC'  | 'FUSE SMD 1A 32V(FAST)F0603FA1000V03'           | 'CHIP'         | ''          | ''   | '20151222'
 'SMLF'     | '1A/32V'     | 'EMPTY'  | 'DK100WFU009'(!)         = ''              | ''             | 'DK100WFU009'            |'F0603XA'| 'IO'  | 'FUSE SMD 1A 32V(FAST)F0603FA1000V03'           | 'CHIP'         | ''          | ''   | '20151222'
 'SMLF'     | '3A/32V'     | 'IC'     | 'DK300WFU006'(!)         = ''              | ''             | 'DK300WFU006'            |'F0603XA'| 'IC'  | 'FUSE SMD 3A/32V(FAST,UL)F0603FA3000V032T'      | 'CHIP'         | ''          | ''   | '20151222'
 'SMLF'     | '3A/32V'     | 'EMPTY'  | 'DK300WFU006'(!)         = ''              | ''             | 'DK300WFU006'            |'F0603XA'| 'IO'  | 'FUSE SMD 3A/32V(FAST,UL)F0603FA3000V032T'      | 'CHIP'         | ''          | ''   | '20151222'
 'SMLF'     | '5A/32V'     | 'IC'     | 'DK800WFU004'(!)         = 'End of Design' | 'Comp-Approve' | 'DK800WFU004'            |'F0603XA'| 'IC'  | 'FUSE SMD 5A/32V/0603FA5000V032T(FAST,UL)'      | 'CHIP'         | ''          | ''   | '20151222'
 'SMLF'     | '5A/32V'     | 'EMPTY'  | 'DK800WFU004'(!)         = 'End of Design' | 'Comp-Approve' | 'DK800WFU004'            |'F0603XA'| 'IO'  | 'FUSE SMD 5A/32V/0603FA5000V032T(FAST,UL)'      | 'CHIP'         | ''          | ''   | '20151222'
 'SMLF'     | '1.5A/63V'   | 'IC'     | 'DK150UFU002'(!)         = ''              | ''             | 'DK150UFU002'            |'F0603XA'| 'IC'  | 'FUSE SMD 1.5A 63V(FAST,UL)F0603FA1500V06'      | 'CHIP'         | ''          | ''   | '20151223'
 'SMLF'     | '1.5A/63V'   | 'EMPTY'  | 'DK150UFU002'(!)         = ''              | ''             | 'DK150UFU002'            |'F0603XA'| 'IO'  | 'FUSE SMD 1.5A 63V(FAST,UL)F0603FA1500V06'      | 'CHIP'         | ''          | ''   | '20151223'
 'SMLF'     | '10A/32V'    | 'IC'     | 'DKA00WFU000'(!)         = ''              | ''             | 'DKA00WFU000'            |'F1206XG'| 'IC'  | 'FUSE SMD10A/32V/AF1206F10.0(FAST,UL/CSA)'      | 'CHIP'         | ''          | ''   | '20160113'
 'SMLF'     | '10A/32V'    | 'EMPTY'  | 'DKA00WFU000'(!)         = ''              | ''             | 'DKA00WFU000'            |'F1206XG'| 'IO'  | 'FUSE SMD10A/32V/AF1206F10.0(FAST,UL/CSA)'      | 'CHIP'         | ''          | ''   | '20160113'
 'SMLF'     | '20A/24V'    | 'IC'     | 'DKK00VFU001'(!)         = ''              | ''             | 'DKK00VFU001'            |'F1206XG'| 'IC'  | 'FUSE SMD 20A 24V(FAST) 1206SFH200F/24'         | 'CHIP'         | ''          | ''   | '20160218'
 'SMLF'     | '20A/24V'    | 'EMPTY'  | 'DKK00VFU001'(!)         = ''              | ''             | 'DKK00VFU001'            |'F1206XG'| 'IO'  | 'FUSE SMD 20A 24V(FAST) 1206SFH200F/24'         | 'CHIP'         | ''          | ''   | '20160218'
 'SMLF'     | '5A/16V'     | 'IC'     | 'DK500SPU004'(!)         = ''              | ''             | 'DK500SPU004'            |'F4112_16R500GPR'| 'IC'  | 'FUSE DIP 5A/16V(POLY,UL/TUV)16R500GPR'         | 'CHIP'         | ''          | ''   | '20160223'
 'SMLF'     | '5A/16V'     | 'EMPTY'  | 'DK500SPU004'(!)         = ''              | ''             | 'DK500SPU004'            |'F4112_16R500GPR'| 'IO'  | 'FUSE DIP 5A/16V(POLY,UL/TUV)16R500GPR'         | 'CHIP'         | ''          | ''   | '20160223'
 'SMLF'     | '5A/16V'     | 'IC'     | 'SP_DK500SPU004'(!)      = ''              | ''             | 'DK500SPU004'            |'G_F4112_16R500GPR'| 'IC'  | 'FUSE DIP 5A/16V(POLY,UL/TUV)16R500GPR_FOR SEL' | 'CHIP'         | ''          | ''   | '20160223'
 'SMLF'     | '5A/16V'     | 'EMPTY'  | 'SP_DK500SPU004'(!)      = ''              | ''             | 'DK500SPU004'            |'G_F4112_16R500GPR'| 'IO'  | 'FUSE DIP 5A/16V(POLY,UL/TUV)16R500GPR_FOR SEL' | 'CHIP'         | ''          | ''   | '20160223'
 'SMLF'     | '15A/125V'   | 'IC'     | 'DKF00XFU001'(!)         = ''              | ''             | 'DKF00XFU001'            |'F2410XA'| 'IC'  | 'FUSE SMD 15A 125V(FAST,UL/PSE)CB61F15A'        | 'CHIP'         | ''          | ''   | '20160225'
 'SMLF'     | '15A/125V'   | 'EMPTY'  | 'DKF00XFU001'(!)         = ''              | ''             | 'DKF00XFU001'            |'F2410XA'| 'IO'  | 'FUSE SMD 15A 125V(FAST,UL/PSE)CB61F15A'        | 'CHIP'         | ''          | ''   | '20160225'
 'SMLF'     | '1.5A/125V'  | 'IC'     | 'DK150XFU000'(!)         = 'End of Design' | 'End of Life'  | 'DK150XFU000'            |'F2410XA_EOL'| 'IC'  | 'FUSE SMD 1.5A/125V(FAST,UL/CSA/CE)SSQ1.5'      | 'CHIP'         | ''          | ''   | '20160225'
 'SMLF'     | '1.5A/125V'  | 'EMPTY'  | 'DK150XFU000'(!)         = 'End of Design' | 'End of Life'  | 'DK150XFU000'            |'F2410XA_EOL'| 'IO'  | 'FUSE SMD 1.5A/125V(FAST,UL/CSA/CE)SSQ1.5'      | 'CHIP'         | ''          | ''   | '20160225'
 'SMLF'     | '15A/125V'   | 'IC'     | 'DKF00VFU004'(!)         = 'End of Design' | 'End of Life'  | 'DKF00VFU004'            |'F2410XA_EOL'| 'IC'  | 'FUSE SMD 15A/125V(FAST,UL/CSA)SSQ 15'          | 'CHIP'         | ''          | ''   | '20160225'
 'SMLF'     | '15A/125V'   | 'EMPTY'  | 'DKF00VFU004'(!)         = 'End of Design' | 'End of Life'  | 'DKF00VFU004'            |'F2410XA_EOL'| 'IO'  | 'FUSE SMD 15A/125V(FAST,UL/CSA)SSQ 15'          | 'CHIP'         | ''          | ''   | '20160225'
 'SMLF'     | '10A/125V'   | 'IC'     | 'DKA00XFU002'(!)         = 'Non-Preferred' | 'End of Life'  | 'DKA00XFU002'            |'F2410XA_EOL'| 'IC'  | 'FUSE SMD 10A 125V(FAST,SSQ10)'                 | 'CHIP'         | ''          | ''   | '20160301'
 'SMLF'     | '10A/125V'   | 'EMPTY'  | 'DKA00XFU002'(!)         = 'Non-Preferred' | 'End of Life'  | 'DKA00XFU002'            |'F2410XA_EOL'| 'IO'  | 'FUSE SMD 10A 125V(FAST,SSQ10)'                 | 'CHIP'         | ''          | ''   | '20160301'
 'SMLF'     | '15A/125V'   | 'IC'     | 'DKF00XFU002'(!)         = ''              | ''             | 'DKF00XFU002'            |'F2410'| 'IC'  | 'FUSE SMD 15A/125V(FAST,UL)0476015.MRSN'        | 'CHIP'         | ''          | ''   | '20160324'
 'SMLF'     | '15A/125V'   | 'EMPTY'  | 'DKF00XFU002'(!)         = ''              | ''             | 'DKF00XFU002'            |'F2410'| 'IO'  | 'FUSE SMD 15A/125V(FAST,UL)0476015.MRSN'        | 'CHIP'         | ''          | ''   | '20160324'
 'SMLF'     | '5A/32V'     | 'IC'     | 'DK500WFU008'(!)         = 'End of Design' | 'End of Life'  | 'DK500WFU008'            |'F0603XB_EOL'| 'IC'  | 'FUSE SMD 5A 32V(FAST,0438005.WR,0603)'         | 'CHIP'         | ''          | ''   | '20160324'
 'SMLF'     | '5A/32V'     | 'EMPTY'  | 'DK500WFU008'(!)         = 'End of Design' | 'End of Life'  | 'DK500WFU008'            |'F0603XB_EOL'| 'IO'  | 'FUSE SMD 5A 32V(FAST,0438005.WR,0603)'         | 'CHIP'         | ''          | ''   | '20160324'
 'SMLF'     | '3A/32V'     | 'IC'     | 'DK300WFU011'(!)         = 'End of Design' | 'End of Life'  | 'DK300WFU011'            |'F0603XB_EOL'| 'IC'  | 'FUSE SMD 3A 32V(FAST,0438003.WR,0603)'         | 'CHIP'         | ''          | ''   | '20160324'
 'SMLF'     | '3A/32V'     | 'EMPTY'  | 'DK300WFU011'(!)         = 'End of Design' | 'End of Life'  | 'DK300WFU011'            |'F0603XB_EOL'| 'IO'  | 'FUSE SMD 3A 32V(FAST,0438003.WR,0603)'         | 'CHIP'         | ''          | ''   | '20160324'
 'SMLF'     | '1A/32V'     | 'IC'     | 'DK100WFU007'(!)         = ''              | ''             | 'DK100WFU007'            |'F0603XB'| 'IC'  | 'FUSE SMD 1A 32V(FAST,0438001.WR,0603)'         | 'CHIP'         | ''          | ''   | '20160324'
 'SMLF'     | '1A/32V'     | 'EMPTY'  | 'DK100WFU007'(!)         = ''              | ''             | 'DK100WFU007'            |'F0603XB'| 'IO'  | 'FUSE SMD 1A 32V(FAST,0438001.WR,0603)'         | 'CHIP'         | ''          | ''   | '20160324'
 'SMLF'     | '30A/125V'   | 'IC'     | 'DKV00XFU000'(!)         = ''              | ''             | 'DKV00XFU000'            |'F4012'| 'IC'  | 'FUSE SMD 30A 125V(FAST,UL/CSA)0456030.ER'      | 'CHIP'         | ''          | ''   | '20160401'
 'SMLF'     | '30A/125V'   | 'EMPTY'  | 'DKV00XFU000'(!)         = ''              | ''             | 'DKV00XFU000'            |'F4012'| 'IO'  | 'FUSE SMD 30A 125V(FAST,UL/CSA)0456030.ER'      | 'CHIP'         | ''          | ''   | '20160401'
 'SMLF'     | '10A/125V'   | 'IC'     | 'DKA00XFU007'(!)         = ''              | ''             | 'DKA00XFU007'            |'F2410'| 'IC'  | 'FUSE SMD 10A 125V(FAST,UL)0451010.MRSN'        | 'CHIP'         | ''          | ''   | '20160407'
 'SMLF'     | '10A/125V'   | 'EMPTY'  | 'DKA00XFU007'(!)         = ''              | ''             | 'DKA00XFU007'            |'F2410'| 'IO'  | 'FUSE SMD 10A 125V(FAST,UL)0451010.MRSN'        | 'CHIP'         | ''          | ''   | '20160407'
 'SMLF'     | '2A/125V'    | 'IC'     | 'DK200XFU001'(!)         = ''              | ''             | 'DK200XFU001'            |'F2410'| 'IC'  | 'FUSE SMD 2A 125V(FAST,UL)0451002.MRL'          | 'CHIP'         | ''          | ''   | '20161017'
 'SMLF'     | '2A/125V'    | 'EMPTY'  | 'DK200XFU001'(!)         = ''              | ''             | 'DK200XFU001'            |'F2410'| 'IO'  | 'FUSE SMD 2A 125V(FAST,UL)0451002.MRL'          | 'CHIP'         | ''          | ''   | '20161017'
 'SMLF'     | '5.0A/125V'  | 'IC'     | 'DK500XFU002'(!)         = ''              | ''             | 'DK500XFU002'            |'F2410_AF2'| 'IC'  | 'FUSE SMD 5.0A,125V(FAST,UL/PSE)AF2-5.00V'      | 'CHIP'         | ''          | ''   | '20170808'
 'SMLF'     | '5.0A/125V'  | 'EMPTY'  | 'DK500XFU002'(!)         = ''              | ''             | 'DK500XFU002'            |'F2410_AF2'| 'IO'  | 'FUSE SMD 5.0A,125V(FAST,UL/PSE)AF2-5.00V'      | 'CHIP'         | ''          | ''   | '20170808'
 'SMLF'     | '3A/125V'    | 'IC'     | 'DK300XFU004'(!)         = ''              | ''             | 'DK300XFU004'            |'F2410_AF2'| 'IC'  | 'FUSE SMD 3A 125V(FAST,UL)AF2-3.00V125TM'       | 'CHIP'         | ''          | ''   | '20170808'
 'SMLF'     | '3A/125V'    | 'EMPTY'  | 'DK300XFU004'(!)         = ''              | ''             | 'DK300XFU004'            |'F2410_AF2'| 'IO'  | 'FUSE SMD 3A 125V(FAST,UL)AF2-3.00V125TM'       | 'CHIP'         | ''          | ''   | '20170808'
 'SMLF'     | '7A/125V'    | 'IC'     | 'DK700XFU001'(!)         = ''              | ''             | 'DK700XFU001'            |'F2410_AF2'| 'IC'  | 'FUSE SMD 7A 125V(FAST,UL)AF2-7.00V125TM'       | 'CHIP'         | ''          | ''   | '20170808'
 'SMLF'     | '7A/125V'    | 'EMPTY'  | 'DK700XFU001'(!)         = ''              | ''             | 'DK700XFU001'            |'F2410_AF2'| 'IO'  | 'FUSE SMD 7A 125V(FAST,UL)AF2-7.00V125TM'       | 'CHIP'         | ''          | ''   | '20170808'
 'SMLF'     | '3A/125V'    | 'IC'     | 'DK300XFU002'(!)         = ''              | ''             | 'DK300XFU002'            |'F2410'| 'IC'  | 'FUSE SMD 3A 125V(FAST,UL)0451003.MRL'          | 'CHIP'         | ''          | ''   | '20170809'
 'SMLF'     | '3A/125V'    | 'EMPTY'  | 'DK300XFU002'(!)         = ''              | ''             | 'DK300XFU002'            |'F2410'| 'IO'  | 'FUSE SMD 3A 125V(FAST,UL)0451003.MRL'          | 'CHIP'         | ''          | ''   | '20170809'
 'SMLF'     | '7A/125V'    | 'IC'     | 'DK700XFU000'(!)         = ''              | ''             | 'DK700XFU000'            |'F2410'| 'IC'  | 'FUSE SMD 7A 125V(FAST,UL)0451007.MRL'          | 'CHIP'         | ''          | ''   | '20170809'
 'SMLF'     | '7A/125V'    | 'EMPTY'  | 'DK700XFU000'(!)         = ''              | ''             | 'DK700XFU000'            |'F2410'| 'IO'  | 'FUSE SMD 7A 125V(FAST,UL)0451007.MRL'          | 'CHIP'         | ''          | ''   | '20170809'
 'SMLF'     | '3.15A/150V' | 'IC'     | 'DK315XFU000'(!)         = ''              | ''             | 'DK315XFU000'            |'F2410_25CF'| 'IC'  | 'FUSE SMD 3.15A 150V(FAST,UL)25CF 3.15AR1'      | 'CHIP'         | ''          | ''   | '20171023'
 'SMLF'     | '3.15A/150V' | 'EMPTY'  | 'DK315XFU000'(!)         = ''              | ''             | 'DK315XFU000'            |'F2410_25CF'| 'IO'  | 'FUSE SMD 3.15A 150V(FAST,UL)25CF 3.15AR1'      | 'CHIP'         | ''          | ''   | '20171023'
 'SMLF'     | '5A/150V'    | 'IC'     | 'DK500XFU003'(!)         = ''              | ''             | 'DK500XFU003'            |'F2410_25CF'| 'IC'  | 'FUSE SMD 5A 150V(FAST,UL)25CF 5AR12A4'         | 'CHIP'         | ''          | ''   | '20171023'
 'SMLF'     | '5A/150V'    | 'EMPTY'  | 'DK500XFU003'(!)         = ''              | ''             | 'DK500XFU003'            |'F2410_25CF'| 'IO'  | 'FUSE SMD 5A 150V(FAST,UL)25CF 5AR12A4'         | 'CHIP'         | ''          | ''   | '20171023'
 'SMLF'     | '0.5A/6V'    | 'IC'     | 'DK050TPU011'(!)         = ''              | ''             | 'DK050TPU011'            |'F1206XH_H30'| 'IC'  | 'FUSE SMD 0.5A,6V(POLY,1206L050YR)'             | 'CHIP'         | ''          | ''   | '20170809'
 'SMLF'     | '0.5A/6V'    | 'EMPTY'  | 'DK050TPU011'(!)         = ''              | ''             | 'DK050TPU011'            |'F1206XH_H30'| 'IO'  | 'FUSE SMD 0.5A,6V(POLY,1206L050YR)'             | 'CHIP'         | ''          | ''   | '20170809'
 'SMLF'     | '1.1A/6V'    | 'IC'     | 'DK110TPU013'(!)         = ''              | ''             | 'DK110TPU013'            |'F0805'| 'IC'  | 'FUSE SMD 1.1A 6V POLY(SPR-P110)'               | 'CHIP'         | ''          | ''   | '20140828'
 'SMLF'     | '1.1A/6V'    | 'EMPTY'  | 'DK110TPU013'(!)         = ''              | ''             | 'DK110TPU013'            |'F0805'| 'IO'  | 'FUSE SMD 1.1A 6V POLY(SPR-P110)'               | 'CHIP'         | ''          | ''   | '20140828'
 'SMLF'     | '100MA/150V' | 'IC'     | 'DK010XFU000'(!)         = ''              | ''             | 'DK010XFU000'            |'F2410_25CF'| 'IC'  | 'FUSE SMD 100MA 150V(FAST,UL)25CF 100MAR1'      | 'CHIP'         | ''          | ''   | '20180419'
 'SMLF'     | '100MA/150V' | 'EMPTY'  | 'DK010XFU000'(!)         = ''              | ''             | 'DK010XFU000'            |'F2410_25CF'| 'IO'  | 'FUSE SMD 100MA 150V(FAST,UL)25CF 100MAR1'      | 'CHIP'         | ''          | ''   | '20180419'
 'SMLF'     | '80A/75V'    | 'IC'     | 'DKZ00UNU000'(!)         = ''              | ''             | 'DKZ00UNU000'            |'F4439_0881'| 'IC'  | 'FUSE SMD 80A 75V(NORMAL,UL)0881080.UR'         | 'CHIP'         | ''          | ''   | '20181108'
 'SMLF'     | '80A/75V'    | 'EMPTY'  | 'DKZ00UNU000'(!)         = ''              | ''             | 'DKZ00UNU000'            |'F4439_0881'| 'IO'  | 'FUSE SMD 80A 75V(NORMAL,UL)0881080.UR'         | 'CHIP'         | ''          | ''   | '20181108'
 'SMLF'     | '0.1A/30V'   | 'IC'     | 'DK010WPU000'(!)         = ''              | ''             | 'DK010WPU000'            |'F1210XA'| 'IC'  | 'FUSE SMD 0.1A,30V(POLY,UL/TUV)1210L010WR'      | 'CHIP'         | ''          | ''   | '20190104'
 'SMLF'     | '0.1A/30V'   | 'EMPTY'  | 'DK010WPU000'(!)         = ''              | ''             | 'DK010WPU000'            |'F1210XA'| 'IO'  | 'FUSE SMD 0.1A,30V(POLY,UL/TUV)1210L010WR'      | 'CHIP'         | ''          | ''   | '20190104'
 'SMLF'     | '1.5A/12V'   | 'IC'     | 'DK150SPU000'(!)         = 'End of Design' | 'Comp-Approve' | 'DK150SPU000'            |'F1812XF'| 'IC'  | 'FUSE SMD1.5A 12V POLY(MINISMDC150F/12)'        | 'CHIP'         | ''          | ''   | '20190304'
 'SMLF'     | '1.5A/12V'   | 'EMPTY'  | 'DK150SPU000'(!)         = 'End of Design' | 'Comp-Approve' | 'DK150SPU000'            |'F1812XF'| 'IO'  | 'FUSE SMD1.5A 12V POLY(MINISMDC150F/12)'        | 'CHIP'         | ''          | ''   | '20190304'
 'SMLF'     | '2.6A/16V'   | 'IC'     | 'DK260SPU000'(!)         = 'End of Design' | 'Comp-Approve' | 'DK260SPU000'            |'F1812XF_H60'| 'IC'  | 'FUSE SMD 2.6A 16V POLY(MINISMDC260F/16-2'      | 'CHIP'         | ''          | ''   | '20190304'
 'SMLF'     | '2.6A/16V'   | 'EMPTY'  | 'DK260SPU000'(!)         = 'End of Design' | 'Comp-Approve' | 'DK260SPU000'            |'F1812XF_H60'| 'IO'  | 'FUSE SMD 2.6A 16V POLY(MINISMDC260F/16-2'      | 'CHIP'         | ''          | ''   | '20190304'
 'SMLF'     | '40A/125V'   | 'IC'     | 'DKZ00XFU000'(!)         = ''              | ''             | 'DKZ00XFU000'            |'F4818'| 'IC'  | 'FUSE SMD 40A 125V(FAST,UL)0456040.DRSD'        | 'CHIP'         | ''          | ''   | '20190418'
 'SMLF'     | '40A/125V'   | 'EMPTY'  | 'DKZ00XFU000'(!)         = ''              | ''             | 'DKZ00XFU000'            |'F4818'| 'IO'  | 'FUSE SMD 40A 125V(FAST,UL)0456040.DRSD'        | 'CHIP'         | ''          | ''   | '20190418'
 'SMLF'     | '1.1A/16V'   | 'IC'     | 'DK110TPU005'(!)         = ''              | ''             | 'DK110TPU005'            |'F1812_1-25'| 'IC'  | 'FUSE SMD 1.1A 16V POLY(SMD1812P110TF/16)'      | 'CHIP'         | ''          | ''   | '20200102'
 'SMLF'     | '1.1A/16V'   | 'EMPTY'  | 'DK110TPU005'(!)         = ''              | ''             | 'DK110TPU005'            |'F1812_1-25'| 'IO'  | 'FUSE SMD 1.1A 16V POLY(SMD1812P110TF/16)'      | 'CHIP'         | ''          | ''   | '20200102'
 'SMLF'     | '2A/32V'     | 'IC'     | 'DK200WFU014'(!)         = ''              | ''             | 'DK200WFU014'            |'F0603XD'| 'IC'  | 'FUSE SMD 2A 32V(FAST,UL) 0686F2000-01'         | 'CHIP'         | ''          | ''   | '20200306'
 'SMLF'     | '2A/32V'     | 'EMPTY'  | 'DK200WFU014'(!)         = ''              | ''             | 'DK200WFU014'            |'F0603XD'| 'IO'  | 'FUSE SMD 2A 32V(FAST,UL) 0686F2000-01'         | 'CHIP'         | ''          | ''   | '20200306'
 'SMLF'     | '7.5A/6V'    | 'IC'     | 'DK750TPU000'(!)         = ''              | ''             | 'DK750TPU000'            |'F1210XA_H40'| 'IC'  | 'FUSE SMD 7.5A 6V POLY(SMD1210P750SLR)'         | 'CHIP'         | ''          | ''   | '20200424'
 'SMLF'     | '7.5A/6V'    | 'EMPTY'  | 'DK750TPU000'(!)         = ''              | ''             | 'DK750TPU000'            |'F1210XA_H40'| 'IO'  | 'FUSE SMD 7.5A 6V POLY(SMD1210P750SLR)'         | 'CHIP'         | ''          | ''   | '20200424'
 'SMLF'     | '1.5A/8V'    | 'IC'     | 'DK150TPU009'(!)         = ''              | ''             | 'DK150TPU009'            |'F1206XH_H40'| 'IC'  | 'FUSE SMD 1.5A,8V(POLY,1206L150THWR)'           | 'CHIP'         | ''          | ''   | '20200526'
 'SMLF'     | '1.5A/8V'    | 'EMPTY'  | 'DK150TPU009'(!)         = ''              | ''             | 'DK150TPU009'            |'F1206XH_H40'| 'IO'  | 'FUSE SMD 1.5A,8V(POLY,1206L150THWR)'           | 'CHIP'         | ''          | ''   | '20200526'
 'SMLF'     | '1A/50V'     | 'IC'     | 'DK100ZHU000'(!)         = ''              | ''             | 'DK100ZHU000'            |'F1206XC'| 'IC'  | 'FUSE SMD1A 50V(HIGH INRUSH,UL)0440001.WR'      | 'CHIP'         | ''          | ''   | '20210311'
 'SMLF'     | '1A/50V'     | 'EMPTY'  | 'DK100ZHU000'(!)         = ''              | ''             | 'DK100ZHU000'            |'F1206XC'| 'IO'  | 'FUSE SMD1A 50V(HIGH INRUSH,UL)0440001.WR'      | 'CHIP'         | ''          | ''   | '20210311'
 'SMLF'     | '1A/75V'     | 'IC'     | 'DK100UHU000'(!)         = ''              | ''             | 'DK100UHU000'            |'F1206XE'| 'IC'  | 'FUSE SMD1A 75V(HIGH INRUSH,UL)0458001.DR'      | 'CHIP'         | ''          | ''   | '20210317'
 'SMLF'     | '1A/75V'     | 'EMPTY'  | 'DK100UHU000'(!)         = ''              | ''             | 'DK100UHU000'            |'F1206XE'| 'IO'  | 'FUSE SMD1A 75V(HIGH INRUSH,UL)0458001.DR'      | 'CHIP'         | ''          | ''   | '20210317'
 'SMLF'     | '100A/75V'   | 'IC'     | 'DKA00UHU000'(!)         = ''              | ''             | 'DKA00UHU000'            |'F4439_0881'| 'IC'  | 'FUSE SMD 100A 75V(HIGH INRUSH)0881100.UR'      | 'CHIP'         | ''          | ''   | '20210407'
 'SMLF'     | '100A/75V'   | 'EMPTY'  | 'DKA00UHU000'(!)         = ''              | ''             | 'DKA00UHU000'            |'F4439_0881'| 'IO'  | 'FUSE SMD 100A 75V(HIGH INRUSH)0881100.UR'      | 'CHIP'         | ''          | ''   | '20210407'
 'SMLF'     | '2.6A/6V'    | 'IC'     | 'DK260TPU008'(!)         = ''              | ''             | 'DK260TPU008'            |'F0805'| 'IC'  | 'FUSE SMD 2.6A 6V POLY(SMD0805P260SLRT)'        | 'CHIP'         | ''          | ''   | '20210519'
 'SMLF'     | '2.6A/6V'    | 'EMPTY'  | 'DK260TPU008'(!)         = ''              | ''             | 'DK260TPU008'            |'F0805'| 'IO'  | 'FUSE SMD 2.6A 6V POLY(SMD0805P260SLRT)'        | 'CHIP'         | ''          | ''   | '20210519'
 'SMLF'     | '3A/6V'      | 'IC'     | 'DK300TPU014'(!)         = ''              | ''             | 'DK300TPU014'            |'F0603_H40'| 'IC'  | 'FUSE SMD 3A 6V POLY(SMD0603P300SLR)'           | 'CHIP'         | ''          | ''   | '20210617'
 'SMLF'     | '3A/6V'      | 'EMPTY'  | 'DK300TPU014'(!)         = ''              | ''             | 'DK300TPU014'            |'F0603_H40'| 'IO'  | 'FUSE SMD 3A 6V POLY(SMD0603P300SLR)'           | 'CHIP'         | ''          | ''   | '20210617'
 'SMLF'     | '1.5A/125V'  | 'IC'     | 'DK150XFU006'(!)         = ''              | ''             | 'DK150XFU006'            |'F2410'| 'IC'  | 'FUSE SMD 1.5A 125V(FAST,UL)045101.5MRL'        | 'CHIP'         | ''          | ''   | '20210913'
 'SMLF'     | '1.5A/125V'  | 'EMPTY'  | 'DK150XFU006'(!)         = ''              | ''             | 'DK150XFU006'            |'F2410'| 'IO'  | 'FUSE SMD 1.5A 125V(FAST,UL)045101.5MRL'        | 'CHIP'         | ''          | ''   | '20210913'
 'SMLF'     | '20A/125V'   | 'IC'     | 'DKK00XFU000'(!)         = ''              | ''             | 'DKK00XFU000'            |'F4012'| 'IC'  | 'FUSE SMD 20A/125V(FAST,UL/CSA)'                | 'CHIP'         | ''          | ''   | '20211207'
 'SMLF'     | '20A/125V'   | 'EMPTY'  | 'DKK00XFU000'(!)         = ''              | ''             | 'DKK00XFU000'            |'F4012'| 'IO'  | 'FUSE SMD 20A/125V(FAST,UL/CSA)'                | 'CHIP'         | ''          | ''   | '20211207'
 'SMLF'     | '1.5A/125V'  | 'IC'     | 'DK150XFU005'(!)         = ''              | ''             | 'DK150XFU005'            |'F2410'| 'IC'  | 'FUSE SMD 1.5A 125V(FAST,UL)0679L1500 AEC'      | 'CHIP'         | ''          | ''   | '20211215'
 'SMLF'     | '1.5A/125V'  | 'EMPTY'  | 'DK150XFU005'(!)         = ''              | ''             | 'DK150XFU005'            |'F2410'| 'IO'  | 'FUSE SMD 1.5A 125V(FAST,UL)0679L1500 AEC'      | 'CHIP'         | ''          | ''   | '20211215'
 'SMLF'     | '2A/6V'      | 'IC'     | 'DK200TPU008'(!)         = 'End of Design' | 'Comp-Approve' | 'DK200TPU008'            |'F1206XH_H63'| 'IC'  | 'FUSE SMD 2A 6V(POLY,1206L200PR)'               | 'CHIP'         | ''          | ''   | '20220429'
 'SMLF'     | '2A/6V'      | 'EMPTY'  | 'DK200TPU008'(!)         = 'End of Design' | 'Comp-Approve' | 'DK200TPU008'            |'F1206XH_H63'| 'IO'  | 'FUSE SMD 2A 6V(POLY,1206L200PR)'               | 'CHIP'         | ''          | ''   | '20220429'
 'SMLF'     | '2A/6V'      | 'IC'     | 'DK200TPU016'(!)         = ''              | ''             | 'DK200TPU016'            |'F1206XH'| 'IC'  | 'FUSE SMD 2A 6V POLY(SMD1206P200SLR)'           | 'CHIP'         | ''          | ''   | '20220506'
 'SMLF'     | '2A/6V'      | 'EMPTY'  | 'DK200TPU016'(!)         = ''              | ''             | 'DK200TPU016'            |'F1206XH'| 'IO'  | 'FUSE SMD 2A 6V POLY(SMD1206P200SLR)'           | 'CHIP'         | ''          | ''   | '20220506'
 'SMLF'     | '0.75A/65V'  | 'IC'     | 'DK075UFU000'(!)         = ''              | ''             | 'DK075UFU000'            |'F0603XE'| 'IC'  | 'FUSE SMD 0.75A 65V(FAST,T0603FF0750TM)'        | 'CHIP'         | ''          | ''   | '20220609'
 'SMLF'     | '0.75A/65V'  | 'EMPTY'  | 'DK075UFU000'(!)         = ''              | ''             | 'DK075UFU000'            |'F0603XE'| 'IO'  | 'FUSE SMD 0.75A 65V(FAST,T0603FF0750TM)'        | 'CHIP'         | ''          | ''   | '20220609'
 'SMLF'     | '20A/125V'   | 'IC'     | 'DKK00XFU001'(!)         = 'Non-Preferred' | 'End of Life'  | 'DKK00XFU001'            |'F4012XA_EOL'| 'IC'  | 'FUSE SMD 20A/125V(FAST,UL)1025HC20-RTR'        | 'CHIP'         | ''          | ''   | '20221205'
 'SMLF'     | '20A/125V'   | 'EMPTY'  | 'DKK00XFU001'(!)         = 'Non-Preferred' | 'End of Life'  | 'DKK00XFU001'            |'F4012XA_EOL'| 'IO'  | 'FUSE SMD 20A/125V(FAST,UL)1025HC20-RTR'        | 'CHIP'         | ''          | ''   | '20221205'
 'SMLF'     | '0.25A/9V'   | 'IC'     | 'DK025TPU002'(!)         = ''              | ''             | 'DK025TPU002'            |'F0603_H30'| 'IC'  | 'FUSE SMD 0.25A 9V POLY(0603L025YR)'            | 'CHIP'         | ''          | ''   | '20230103'
 'SMLF'     | '0.25A/9V'   | 'EMPTY'  | 'DK025TPU002'(!)         = ''              | ''             | 'DK025TPU002'            |'F0603_H30'| 'IO'  | 'FUSE SMD 0.25A 9V POLY(0603L025YR)'            | 'CHIP'         | ''          | ''   | '20230103'
 'SMLF'     | '0.02A/60V'  | 'IC'     | 'DK002ZPU001'(!)         = ''              | ''             | 'DK002ZPU001'            |'F0603_H40'| 'IC'  | 'FUSE SMD 0.02A 60V POLY(0603L002/60YR)'        | 'CHIP'         | ''          | ''   | '20230710'
 'SMLF'     | '0.02A/60V'  | 'EMPTY'  | 'DK002ZPU001'(!)         = ''              | ''             | 'DK002ZPU001'            |'F0603_H40'| 'IO'  | 'FUSE SMD 0.02A 60V POLY(0603L002/60YR)'        | 'CHIP'         | ''          | ''   | '20230710'
 'SMLF'     | '0.02A/60V'  | 'IC'     | 'DK002ZPU002'(!)         = ''              | ''             | 'DK002ZPU002'            |'F0603_H40'| 'IC'  | 'FUSE SMD 0.02A 60V POLY(SMD0603P002TF)'        | 'CHIP'         | ''          | ''   | '20230731'
 'SMLF'     | '0.02A/60V'  | 'EMPTY'  | 'DK002ZPU002'(!)         = ''              | ''             | 'DK002ZPU002'            |'F0603_H40'| 'IO'  | 'FUSE SMD 0.02A 60V POLY(SMD0603P002TF)'        | 'CHIP'         | ''          | ''   | '20230731'
 'SMLF'     | '1A/6V'      | 'IC'     | 'DK100TPU004SEL1'(!)     = ''              | ''             | 'DK100TPU004SEL1'        |'F0603_H30'| 'IC'  | 'FUSE SMD 1A 6V POLY(SMD0603P SELASN'           | 'CHIP'         | ''          | ''   | '20141218'
 'SMLF'     | '1A/6V'      | 'EMPTY'  | 'DK100TPU004SEL1'(!)     = ''              | ''             | 'DK100TPU004SEL1'        |'F0603_H30'| 'IO'  | 'FUSE SMD 1A 6V POLY(SMD0603P SELASN'           | 'CHIP'         | ''          | ''   | '20141218'
 'SMLF'     | '1.5A/8V'    | 'IC'     | 'DK150TPU009SEL1'(!)     = ''              | ''             | 'DK150TPU009SEL1'        |'F1206XH_H40'| 'IC'  | 'FUSE SMD1.5A,8V(POLY,1206L150THWR SELASN'      | 'CHIP'         | ''          | ''   | '20200526'
 'SMLF'     | '1.5A/8V'    | 'EMPTY'  | 'DK150TPU009SEL1'(!)     = ''              | ''             | 'DK150TPU009SEL1'        |'F1206XH_H40'| 'IO'  | 'FUSE SMD1.5A,8V(POLY,1206L150THWR SELASN'      | 'CHIP'         | ''          | ''   | '20200526'
 'SMLF'     | '1.5A/125V'  | 'IC'     | 'DK150XFU006SEL1'(!)     = ''              | ''             | 'DK150XFU006SEL1'        |'F2410'| 'IC'  | 'FUSESMD1.5A 125V(FAST,UL)045101.5MRLSELA'      | 'CHIP'         | ''          | ''   | '20210913'
 'SMLF'     | '1.5A/125V'  | 'EMPTY'  | 'DK150XFU006SEL1'(!)     = ''              | ''             | 'DK150XFU006SEL1'        |'F2410'| 'IO'  | 'FUSESMD1.5A 125V(FAST,UL)045101.5MRLSELA'      | 'CHIP'         | ''          | ''   | '20210913'
 'SMLF'     | '4.5A/6V'    | 'IC'     | 'DK450TPU000SEL1'(!)     = ''              | ''             | 'DK450TPU000SEL1'        |'F1210XA'| 'IC'  | 'FUSE SMD 4.5A 6V POLY(1210L45 SELASN'          | 'CHIP'         | ''          | ''   | '20140708'
 'SMLF'     | '4.5A/6V'    | 'EMPTY'  | 'DK450TPU000SEL1'(!)     = ''              | ''             | 'DK450TPU000SEL1'        |'F1210XA'| 'IO'  | 'FUSE SMD 4.5A 6V POLY(1210L45 SELASN'          | 'CHIP'         | ''          | ''   | '20140708'
 'SMLF'     | '30A/125V'   | 'IC'     | 'DKV00XFU000SEL1'(!)     = ''              | ''             | 'DKV00XFU000SEL1'        |'F4012'| 'IC'  | 'FUSESMD30A 125V(FAST,UL/CSA)04560 SELASN'      | 'CHIP'         | ''          | ''   | '20160401'
 'SMLF'     | '30A/125V'   | 'EMPTY'  | 'DKV00XFU000SEL1'(!)     = ''              | ''             | 'DKV00XFU000SEL1'        |'F4012'| 'IO'  | 'FUSESMD30A 125V(FAST,UL/CSA)04560 SELASN'      | 'CHIP'         | ''          | ''   | '20160401'

END_PART

END.

